# S9S_MB_2U (Grand Teton) — schematic netlist excerpt (pin names and nets, part order shuffled) for the footprints in the layout excerpt that follows; sources: Cadence DE-HDL packaged netlist, KiCad conversion of 03242023_DA0F0TMBIJ0_F0T_Motherboard_J_brd_V01_OCP.brd

C1185  Q_CAP  22UF 4V 20% X6S  pkg C0603  page 189 : A = P1V05_PCH_AUX ; B = GND
PC1683  Q_CAP  22UF 16V 20% X6S  pkg C0805  page 290 : A = SW_P12V_PVCCFA_EHV_FIVRA_CPU1_R ; B = GND
R1247  Q_RES  0 5% CHIP  pkg 0402LF  page 203 : A = FM_PCH_CPU_PWR_DEBUG_N ; B = FM_CPU_FBRK_DEBUG_N

(kicad_pcb
	(version 20260206)
	(generator "pcbnew")
	(generator_version "10.0")
	(general
		(thickness 1.6)
		(legacy_teardrops no)
	)
	(paper "A4")
	(title_block
		(title "03242023_DA0F0TMBIJ0_F0T_Motherboard_J_brd_V01_OCP.brd")
		(comment 1 "Grand Teton / footprints 5917-5919 of 6105")
	)
	(layers
		(0 "F.Cu" signal "TOP")
		(4 "In1.Cu" signal "GND")
		(6 "In2.Cu" signal "IN1")
		(8 "In3.Cu" signal "GND1")
		(10 "In4.Cu" signal "IN2")
		(12 "In5.Cu" signal "GND2")
		(14 "In6.Cu" signal "IN3")
		(16 "In7.Cu" signal "GND3")
		(18 "In8.Cu" signal "VCC")
		(20 "In9.Cu" signal "VCC1")
		(22 "In10.Cu" signal "GND4")
		(24 "In11.Cu" signal "IN4")
		(26 "In12.Cu" signal "GND5")
		(28 "In13.Cu" signal "IN5")
		(30 "In14.Cu" signal "GND6")
		(32 "In15.Cu" signal "IN6")
		(34 "In16.Cu" signal "GND7")
		(2 "B.Cu" signal "BOTTOM")
		(9 "F.Adhes" user "F.Adhesive")
		(11 "B.Adhes" user "B.Adhesive")
		(13 "F.Paste" user "Package Geometry/Pastemask Top")
		(15 "B.Paste" user "Package Geometry/Pastemask Bottom")
		(5 "F.SilkS" user "Ref Des/Silkscreen Top")
		(7 "B.SilkS" user "Ref Des/Silkscreen Bottom")
		(1 "F.Mask" user "Board Geometry/Soldermask Top")
		(3 "B.Mask" user "Board Geometry/Soldermask Bottom")
		(17 "Dwgs.User" user "User.Drawings")
		(19 "Cmts.User" user "User.Comments")
		(21 "Eco1.User" user "User.Eco1")
		(23 "Eco2.User" user "User.Eco2")
		(25 "Edge.Cuts" user "Board Geometry/Outline")
		(27 "Margin" user)
		(31 "F.CrtYd" user "Package Geometry/Place Bound Top")
		(29 "B.CrtYd" user "Package Geometry/Place Bound Bottom")
		(35 "F.Fab" user "Ref Des/Assembly Top")
		(33 "B.Fab" user "Ref Des/Assembly Bottom")
	)
	(footprint ""
		(layer "B.Cu")
		(at 323.001132 -59.742324)
		(property "Reference" "R1247"
			(at 0 0 0)
			(layer "B.SilkS")
			(hide yes)
			(effects
				(font
					(size 1.27 1.27)
				)
				(justify mirror)
			)
		)
		(property "Value" ""
			(at 0 0 0)
			(layer "B.Fab")
			(effects
				(font
					(size 1.27 1.27)
				)
				(justify mirror)
			)
		)
		(duplicate_pad_numbers_are_jumpers no)
		(fp_line
			(start -0.7874 -0.4064)
			(end -0.7874 0.4064)
			(stroke
				(width 0.1524)
				(type default)
			)
			(layer "B.SilkS")
		)
		(fp_line
			(start -0.7874 0.4064)
			(end 0.7874 0.4064)
			(stroke
				(width 0.1524)
				(type default)
			)
			(layer "B.SilkS")
		)
		(fp_line
			(start 0.7874 -0.4064)
			(end -0.7874 -0.4064)
			(stroke
				(width 0.1524)
				(type default)
			)
			(layer "B.SilkS")
		)
		(fp_line
			(start 0.7874 0.4064)
			(end 0.7874 -0.4064)
			(stroke
				(width 0.1524)
				(type default)
			)
			(layer "B.SilkS")
		)
		(fp_line
			(start -0.67945 -0.3048)
			(end -0.67945 0.3048)
			(stroke
				(width 0.1)
				(type default)
			)
			(layer "B.Fab")
		)
		(fp_line
			(start -0.67945 0.3048)
			(end -0.120396 0.3048)
			(stroke
				(width 0.1)
				(type default)
			)
			(layer "B.Fab")
		)
		(fp_line
			(start -0.12065 -0.3048)
			(end -0.67945 -0.3048)
			(stroke
				(width 0.1)
				(type default)
			)
			(layer "B.Fab")
		)
		(fp_line
			(start -0.12065 -0.2794)
			(end -0.12065 -0.3048)
			(stroke
				(width 0.1)
				(type default)
			)
			(layer "B.Fab")
		)
		(fp_line
			(start -0.120396 0.2794)
			(end 0.12065 0.2794)
			(stroke
				(width 0.1)
				(type default)
			)
			(layer "B.Fab")
		)
		(fp_line
			(start -0.120396 0.3048)
			(end -0.120396 0.2794)
			(stroke
				(width 0.1)
				(type default)
			)
			(layer "B.Fab")
		)
		(fp_line
			(start 0.12065 -0.305054)
			(end 0.12065 -0.2794)
			(stroke
				(width 0.1)
				(type default)
			)
			(layer "B.Fab")
		)
		(fp_line
			(start 0.12065 -0.2794)
			(end -0.12065 -0.2794)
			(stroke
				(width 0.1)
				(type default)
			)
			(layer "B.Fab")
		)
		(fp_line
			(start 0.12065 0.2794)
			(end 0.12065 0.3048)
			(stroke
				(width 0.1)
				(type default)
			)
			(layer "B.Fab")
		)
		(fp_line
			(start 0.12065 0.3048)
			(end 0.67945 0.3048)
			(stroke
				(width 0.1)
				(type default)
			)
			(layer "B.Fab")
		)
		(fp_line
			(start 0.67945 -0.305054)
			(end 0.12065 -0.305054)
			(stroke
				(width 0.1)
				(type default)
			)
			(layer "B.Fab")
		)
		(fp_line
			(start 0.67945 0.3048)
			(end 0.67945 -0.305054)
			(stroke
				(width 0.1)
				(type default)
			)
			(layer "B.Fab")
		)
		(pad "1" smd circle
			(at 0.40005 0 180)
			(size 0 0)
			(layers "B.Cu" "B.Mask" "B.Paste")
			(net "FM_PCH_CPU_PWR_DEBUG_N")
		)
		(pad "2" smd circle
			(at -0.40005 0 180)
			(size 0 0)
			(layers "B.Cu" "B.Mask" "B.Paste")
			(net "FM_CPU_FBRK_DEBUG_N")
		)
	)
	(footprint ""
		(layer "B.Cu")
		(at 176.317148 -358.09936 180)
		(property "Reference" "PC1683"
			(at 0 0 0)
			(layer "B.SilkS")
			(hide yes)
			(effects
				(font
					(size 1.27 1.27)
				)
				(justify mirror)
			)
		)
		(property "Value" ""
			(at 0 0 0)
			(layer "B.Fab")
			(effects
				(font
					(size 1.27 1.27)
				)
				(justify mirror)
			)
		)
		(duplicate_pad_numbers_are_jumpers no)
		(fp_line
			(start 1.524 0.762)
			(end 1.524 -0.762)
			(stroke
				(width 0.1524)
				(type default)
			)
			(layer "B.SilkS")
		)
		(fp_line
			(start 1.524 -0.762)
			(end -1.524 -0.762)
			(stroke
				(width 0.1524)
				(type default)
			)
			(layer "B.SilkS")
		)
		(fp_line
			(start -1.524 0.762)
			(end 1.524 0.762)
			(stroke
				(width 0.1524)
				(type default)
			)
			(layer "B.SilkS")
		)
		(fp_line
			(start -1.524 -0.762)
			(end -1.524 0.762)
			(stroke
				(width 0.1524)
				(type default)
			)
			(layer "B.SilkS")
		)
		(fp_line
			(start 1.1049 0.724916)
			(end -1.1049 0.724916)
			(stroke
				(width 0.1)
				(type default)
			)
			(layer "B.Fab")
		)
		(fp_line
			(start 1.1049 -0.724916)
			(end 1.1049 0.724916)
			(stroke
				(width 0.1)
				(type default)
			)
			(layer "B.Fab")
		)
		(fp_line
			(start -1.1049 0.724916)
			(end -1.1049 -0.724916)
			(stroke
				(width 0.1)
				(type default)
			)
			(layer "B.Fab")
		)
		(fp_line
			(start -1.1049 -0.724916)
			(end 1.1049 -0.724916)
			(stroke
				(width 0.1)
				(type default)
			)
			(layer "B.Fab")
		)
		(pad "1" smd rect
			(at 0.889 0 180)
			(size 1.016 1.27)
			(layers "B.Cu" "B.Mask" "B.Paste")
			(net "SW_P12V_PVCCFA_EHV_FIVRA_CPU1_R")
		)
		(pad "2" smd rect
			(at -0.889 0 180)
			(size 1.016 1.27)
			(layers "B.Cu" "B.Mask" "B.Paste")
			(net "GND")
		)
	)
	(footprint ""
		(layer "B.Cu")
		(at 297.525948 -48.409352)
		(property "Reference" "C1185"
			(at 0 0 0)
			(layer "B.SilkS")
			(hide yes)
			(effects
				(font
					(size 1.27 1.27)
				)
				(justify mirror)
			)
		)
		(property "Value" ""
			(at 0 0 0)
			(layer "B.Fab")
			(effects
				(font
					(size 1.27 1.27)
				)
				(justify mirror)
			)
		)
		(duplicate_pad_numbers_are_jumpers no)
		(fp_line
			(start -1.2954 -0.5842)
			(end -1.2954 0.5842)
			(stroke
				(width 0.1524)
				(type default)
			)
			(layer "B.SilkS")
		)
		(fp_line
			(start -1.2954 0.5842)
			(end 1.2954 0.5842)
			(stroke
				(width 0.1524)
				(type default)
			)
			(layer "B.SilkS")
		)
		(fp_line
			(start 0 -0.5842)
			(end 0 0.5842)
			(stroke
				(width 0.1524)
				(type default)
			)
			(layer "B.SilkS")
		)
		(fp_line
			(start 1.2954 -0.5842)
			(end -1.2954 -0.5842)
			(stroke
				(width 0.1524)
				(type default)
			)
			(layer "B.SilkS")
		)
		(fp_line
			(start 1.2954 0.5842)
			(end 1.2954 -0.5842)
			(stroke
				(width 0.1524)
				(type default)
			)
			(layer "B.SilkS")
		)
		(fp_line
			(start -1.1938 -0.4064)
			(end -1.1938 0.4064)
			(stroke
				(width 0.1)
				(type default)
			)
			(layer "B.Fab")
		)
		(fp_line
			(start -1.1938 0.4064)
			(end -0.8636 0.4064)
			(stroke
				(width 0.1)
				(type default)
			)
			(layer "B.Fab")
		)
		(fp_line
			(start -0.8636 -0.4572)
			(end -0.8636 -0.4064)
			(stroke
				(width 0.1)
				(type default)
			)
			(layer "B.Fab")
		)
		(fp_line
			(start -0.8636 -0.4064)
			(end -1.1938 -0.4064)
			(stroke
				(width 0.1)
				(type default)
			)
			(layer "B.Fab")
		)
		(fp_line
			(start -0.8636 0.4064)
			(end -0.8636 0.4572)
			(stroke
				(width 0.1)
				(type default)
			)
			(layer "B.Fab")
		)
		(fp_line
			(start -0.8636 0.4572)
			(end 0.8636 0.4572)
			(stroke
				(width 0.1)
				(type default)
			)
			(layer "B.Fab")
		)
		(fp_line
			(start 0.8636 -0.4572)
			(end -0.8636 -0.4572)
			(stroke
				(width 0.1)
				(type default)
			)
			(layer "B.Fab")
		)
		(fp_line
			(start 0.8636 -0.4064)
			(end 0.8636 -0.4572)
			(stroke
				(width 0.1)
				(type default)
			)
			(layer "B.Fab")
		)
		(fp_line
			(start 0.8636 0.4064)
			(end 1.1938 0.4064)
			(stroke
				(width 0.1)
				(type default)
			)
			(layer "B.Fab")
		)
		(fp_line
			(start 0.8636 0.4572)
			(end 0.8636 0.4064)
			(stroke
				(width 0.1)
				(type default)
			)
			(layer "B.Fab")
		)
		(fp_line
			(start 1.1938 -0.4064)
			(end 0.8636 -0.4064)
			(stroke
				(width 0.1)
				(type default)
			)
			(layer "B.Fab")
		)
		(fp_line
			(start 1.1938 0.4064)
			(end 1.1938 -0.4064)
			(stroke
				(width 0.1)
				(type default)
			)
			(layer "B.Fab")
		)
		(pad "1" smd rect
			(at 0.7366 0 270)
			(size 0.7112 0.8128)
			(layers "B.Cu" "B.Mask" "B.Paste")
			(net "P1V05_PCH_AUX")
		)
		(pad "2" smd rect
			(at -0.7366 0 270)
			(size 0.7112 0.8128)
			(layers "B.Cu" "B.Mask" "B.Paste")
			(net "GND")
		)
	)
)
